# S9S_MB_2U (Grand Teton) — schematic parts with pin connectivity, parts 5876–5879 of 6093; source: Cadence DE-HDL packaged netlist (pstxprt.dat, pstxnet.dat, pstchip.dat)

U1  SOCKET4677_AZIF0045P001C01CS  SOCKET4677_AZIF0045-P001C01CS IO  pkg SOCKET4677_82X64-5XA_H466  page 44  (pins 4579-4677 of 4677)
  V75  VSS1806  POWER  = GND
  V77  VSS1810  POWER  = GND
  V79  VSS1811  POWER  = GND
  V81  UPI2_TX_DP7  OUT  = UPI_CPU1_CPU0_P2P2_DP<7>
  V83  UPI2_TX_DN8  OUT  = UPI_CPU1_CPU0_P2P2_DN<8>
  V85  PE4_TX_DP3  OUT  = P5E_CPU1_PE4_TX_DP<3>
  V87  VSS1813  POWER  = GND
  V89  PE4_RX_DN3  IN  = P5E_CPU1_PE4_RX_DN<3>
  V91  VSS1807  POWER  = GND
  W1  VSS1808  POWER  = GND
  W3  UPI0_TX_DP5  OUT  = UPI_CPU1_CPU0_P0P1_DP<5>
  W5  VSS1814  POWER  = GND
  W7  UPI0_RX_DP4  IN  = UPI_CPU0_CPU1_P1P0_DP<4>
  W9  VSS1819  POWER  = GND
  W11  PE0_RX_DP4  IN  = P5E_CPU1_PE0_RX_DP<4>
  W13  VSS1809  POWER  = GND
  W15  PE0_TX_DP3  OUT  = P5E_CPU1_PE0_TX_DP<3>
  W17  RSVD165  BI  = NC_CPU1_HBM1_VIEWDIG0
  W19  DDR2_SB_DQ23  BI  = M_C_CPU1_SB_DQ<23>
  W21  DDR2_SB_DQS_DN7  BI  = M_C_CPU1_SB_DQS_DN<7>
  W23  DDR2_SB_DQ18  BI  = M_C_CPU1_SB_DQ<18>
  W25  DDR1_SB_DQ7  BI  = M_B_CPU1_SB_DQ<7>
  W27  DDR1_SB_DQS_DN5  BI  = M_B_CPU1_SB_DQS_DN<5>
  W29  DDR1_SB_DQ2  BI  = M_B_CPU1_SB_DQ<2>
  W31  DDR2_SB_ECC3  BI  = M_C_CPU1_SB_CB<3>
  W33  DDR2_SB_DQS_DN4  BI  = M_C_CPU1_SB_DQS_DN<4>
  W35  DDR2_SB_ECC6  BI  = M_C_CPU1_SB_CB<6>
  W37  DDR2_SB_CS_N3  OUT  = M_C_CPU1_SB_CS_N<3>
  W39  VSS1816  POWER  = GND
  W41  DDR2_SB_CA3  OUT  = M_C_CPU1_SB_CA<3>
  W43  DDR1_SA_PAR  OUT  = M_B_CPU1_SA_PAR
  W45  DDR1_CLK_DN1  OUT  = M_B_CPU1_CLK_DN<1>
  W48  DDR2_SB_CA0  OUT  = M_C_CPU1_SB_CA<0>
  W50  DDR2_SA_CA5  OUT  = M_C_CPU1_SA_CA<5>
  W52  VSS1815  POWER  = GND
  W54  DDR2_SA_CS_N2  OUT  = M_C_CPU1_SA_CS_N<2>
  W56  DDR1_SA_DQ31  BI  = M_B_CPU1_SA_DQ<31>
  W58  DDR1_SA_DQS_DP8  BI  = M_B_CPU1_SA_DQS_DP<8>
  W60  DDR1_SA_DQ26  BI  = M_B_CPU1_SA_DQ<26>
  W62  DDR2_SA_DQ23  BI  = M_C_CPU1_SA_DQ<23>
  W64  DDR2_SA_DQS_DP7  BI  = M_C_CPU1_SA_DQS_DP<7>
  W66  DDR2_SA_DQ18  BI  = M_C_CPU1_SA_DQ<18>
  W68  DDR1_SA_DQ15  BI  = M_B_CPU1_SA_DQ<15>
  W70  DDR1_SA_DQS_DP6  BI  = M_B_CPU1_SA_DQS_DP<6>
  W72  DDR1_SA_DQ10  BI  = M_B_CPU1_SA_DQ<10>
  W74  DDR2_SA_DQ7  BI  = M_C_CPU1_SA_DQ<7>
  W76  DDR2_SA_DQS_DN5  BI  = M_C_CPU1_SA_DQS_DN<5>
  W78  DDR2_SA_DQ2  BI  = M_C_CPU1_SA_DQ<2>
  W80  VCCFA_EHV_FIVRA101  POWER  = PVCCFA_EHV_FIVRA_CPU1
  W82  UPI2_TX_DP9  OUT  = UPI_CPU1_CPU0_P2P2_DP<9>
  W84  VSS1817  POWER  = GND
  W86  PE4_TX_DN4  OUT  = P5E_CPU1_PE4_TX_DN<4>
  W88  VSS1818  POWER  = GND
  W90  PE4_RX_DP4  IN  = P5E_CPU1_PE4_RX_DP<4>
  Y2  UPI0_TX_DN5  OUT  = UPI_CPU1_CPU0_P0P1_DN<5>
  Y4  VSS1826  POWER  = GND
  Y6  UPI0_RX_DP5  IN  = UPI_CPU0_CPU1_P1P0_DP<5>
  Y8  VSS1832  POWER  = GND
  Y10  PE0_RX_DP5  IN  = P5E_CPU1_PE0_RX_DP<5>
  Y12  VSS1820  POWER  = GND
  Y14  PE0_TX_DP4  OUT  = P5E_CPU1_PE0_TX_DP<4>
  Y16  VSS1821  POWER  = GND
  Y18  VSS1822  POWER  = GND
  Y20  DDR2_SB_DQ22  BI  = M_C_CPU1_SB_DQ<22>
  Y22  DDR2_SB_DQ19  BI  = M_C_CPU1_SB_DQ<19>
  Y24  VSS1823  POWER  = GND
  Y26  DDR1_SB_DQ6  BI  = M_B_CPU1_SB_DQ<6>
  Y28  DDR1_SB_DQ3  BI  = M_B_CPU1_SB_DQ<3>
  Y30  VSS1824  POWER  = GND
  Y32  DDR2_SB_ECC2  BI  = M_C_CPU1_SB_CB<2>
  Y34  DDR2_SB_ECC7  BI  = M_C_CPU1_SB_CB<7>
  Y36  VSS1825  POWER  = GND
  Y38  DDR2_SB_CS_N2  OUT  = M_C_CPU1_SB_CS_N<2>
  Y40  DDR2_SB_CA5  OUT  = M_C_CPU1_SB_CA<5>
  Y42  VSS1827  POWER  = GND
  Y44  DDR1_SA_CA6  OUT  = M_B_CPU1_SA_CA<6>
  Y47  DDR2_SB_CA1  OUT  = M_C_CPU1_SB_CA<1>
  Y49  VSS1830  POWER  = GND
  Y51  DDR2_SA_CA3  OUT  = M_C_CPU1_SA_CA<3>
  Y53  DDR2_SA_CS_N3  OUT  = M_C_CPU1_SA_CS_N<3>
  Y55  VSS1831  POWER  = GND
  Y57  DDR1_SA_DQ30  BI  = M_B_CPU1_SA_DQ<30>
  Y59  DDR1_SA_DQ27  BI  = M_B_CPU1_SA_DQ<27>
  Y61  VSS1828  POWER  = GND
  Y63  DDR2_SA_DQ22  BI  = M_C_CPU1_SA_DQ<22>
  Y65  DDR2_SA_DQ19  BI  = M_C_CPU1_SA_DQ<19>
  Y67  VSS1829  POWER  = GND
  Y69  DDR1_SA_DQ14  BI  = M_B_CPU1_SA_DQ<14>
  Y71  DDR1_SA_DQ11  BI  = M_B_CPU1_SA_DQ<11>
  Y73  VSS1833  POWER  = GND
  Y75  DDR2_SA_DQ6  BI  = M_C_CPU1_SA_DQ<6>
  Y77  DDR2_SA_DQ3  BI  = M_C_CPU1_SA_DQ<3>
  Y79  VCCFA_EHV_FIVRA102  POWER  = PVCCFA_EHV_FIVRA_CPU1
  Y81  UPI2_TX_DN9  OUT  = UPI_CPU1_CPU0_P2P2_DN<9>
  Y83  UPI2_TX_DP8  OUT  = UPI_CPU1_CPU0_P2P2_DP<8>
  Y85  VCCFA_EHV_FIVRA103  POWER  = PVCCFA_EHV_FIVRA_CPU1
  Y87  PE4_TX_DP4  OUT  = P5E_CPU1_PE4_TX_DP<4>
  Y89  VCCFA_EHV_FIVRA104  POWER  = PVCCFA_EHV_FIVRA_CPU1
  Y91  PE4_RX_DN4  IN  = P5E_CPU1_PE4_RX_DN<4>

U1_BL  TP  NA  pkg TP_BOM ONLY  page 312 : 1 = NC
U1_BP  TP  NA  pkg TP_BOM ONLY  page 312 : 1 = NC
U1_DC  TP  NA  pkg TP_BOM ONLY  page 312 : 1 = NC
